(kicad_pcb
	(version 20260206)
	(generator "pcbnew")
	(generator_version "10.0")
	(general
		(thickness 1.6)
		(legacy_teardrops no)
	)
	(paper "A4")
	(title_block
		(title "01162023_DA0F0TEBIF0_F0T_Expander_BD_F_brd_V02_OCP.brd")
		(comment 1 "Grand Teton / footprints 7533-7539 of 9728")
	)
	(layers
		(0 "F.Cu" signal "TOP")
		(4 "In1.Cu" signal "GND")
		(6 "In2.Cu" signal "VCC")
		(8 "In3.Cu" signal "VCC1")
		(10 "In4.Cu" signal "GND1")
		(12 "In5.Cu" signal "IN1")
		(14 "In6.Cu" signal "GND2")
		(16 "In7.Cu" signal "IN2")
		(18 "In8.Cu" signal "GND3")
		(20 "In9.Cu" signal "IN3")
		(22 "In10.Cu" signal "GND4")
		(24 "In11.Cu" signal "IN4")
		(26 "In12.Cu" signal "GND5")
		(28 "In13.Cu" signal "IN5")
		(30 "In14.Cu" signal "GND6")
		(32 "In15.Cu" signal "IN6")
		(34 "In16.Cu" signal "GND7")
		(2 "B.Cu" signal "BOTTOM")
		(9 "F.Adhes" user "F.Adhesive")
		(11 "B.Adhes" user "B.Adhesive")
		(13 "F.Paste" user "Package Geometry/Pastemask Top")
		(15 "B.Paste" user "Package Geometry/Pastemask Bottom")
		(5 "F.SilkS" user "Ref Des/Silkscreen Top")
		(7 "B.SilkS" user "Ref Des/Silkscreen Bottom")
		(1 "F.Mask" user "Board Geometry/Soldermask Top")
		(3 "B.Mask" user "Board Geometry/Soldermask Bottom")
		(17 "Dwgs.User" user "User.Drawings")
		(19 "Cmts.User" user "User.Comments")
		(21 "Eco1.User" user "User.Eco1")
		(23 "Eco2.User" user "User.Eco2")
		(25 "Edge.Cuts" user "Board Geometry/Outline")
		(27 "Margin" user)
		(31 "F.CrtYd" user "Package Geometry/Place Bound Top")
		(29 "B.CrtYd" user "Package Geometry/Place Bound Bottom")
		(35 "F.Fab" user "Ref Des/Assembly Top")
		(33 "B.Fab" user "Ref Des/Assembly Bottom")
	)
	(footprint ""
		(layer "B.Cu")
		(at 182.17642 -111.334042 180)
		(property "Reference" "R189"
			(at 0 0 0)
			(layer "B.SilkS")
			(hide yes)
			(effects
				(font
					(size 1.27 1.27)
				)
				(justify mirror)
			)
		)
		(property "Value" ""
			(at 0 0 0)
			(layer "B.Fab")
			(effects
				(font
					(size 1.27 1.27)
				)
				(justify mirror)
			)
		)
		(duplicate_pad_numbers_are_jumpers no)
		(fp_line
			(start 0.7874 0.4064)
			(end 0.7874 -0.4064)
			(stroke
				(width 0.1524)
				(type default)
			)
			(layer "B.SilkS")
		)
		(fp_line
			(start 0.7874 -0.4064)
			(end -0.7874 -0.4064)
			(stroke
				(width 0.1524)
				(type default)
			)
			(layer "B.SilkS")
		)
		(fp_line
			(start -0.7874 0.4064)
			(end 0.7874 0.4064)
			(stroke
				(width 0.1524)
				(type default)
			)
			(layer "B.SilkS")
		)
		(fp_line
			(start -0.7874 -0.4064)
			(end -0.7874 0.4064)
			(stroke
				(width 0.1524)
				(type default)
			)
			(layer "B.SilkS")
		)
		(fp_line
			(start 0.67945 0.3048)
			(end 0.67945 -0.305054)
			(stroke
				(width 0.1)
				(type default)
			)
			(layer "B.Fab")
		)
		(fp_line
			(start 0.67945 -0.305054)
			(end 0.12065 -0.305054)
			(stroke
				(width 0.1)
				(type default)
			)
			(layer "B.Fab")
		)
		(fp_line
			(start 0.12065 0.3048)
			(end 0.67945 0.3048)
			(stroke
				(width 0.1)
				(type default)
			)
			(layer "B.Fab")
		)
		(fp_line
			(start 0.12065 0.2794)
			(end 0.12065 0.3048)
			(stroke
				(width 0.1)
				(type default)
			)
			(layer "B.Fab")
		)
		(fp_line
			(start 0.12065 -0.2794)
			(end -0.12065 -0.2794)
			(stroke
				(width 0.1)
				(type default)
			)
			(layer "B.Fab")
		)
		(fp_line
			(start 0.12065 -0.305054)
			(end 0.12065 -0.2794)
			(stroke
				(width 0.1)
				(type default)
			)
			(layer "B.Fab")
		)
		(fp_line
			(start -0.120396 0.3048)
			(end -0.120396 0.2794)
			(stroke
				(width 0.1)
				(type default)
			)
			(layer "B.Fab")
		)
		(fp_line
			(start -0.120396 0.2794)
			(end 0.12065 0.2794)
			(stroke
				(width 0.1)
				(type default)
			)
			(layer "B.Fab")
		)
		(fp_line
			(start -0.12065 -0.2794)
			(end -0.12065 -0.3048)
			(stroke
				(width 0.1)
				(type default)
			)
			(layer "B.Fab")
		)
		(fp_line
			(start -0.12065 -0.3048)
			(end -0.67945 -0.3048)
			(stroke
				(width 0.1)
				(type default)
			)
			(layer "B.Fab")
		)
		(fp_line
			(start -0.67945 0.3048)
			(end -0.120396 0.3048)
			(stroke
				(width 0.1)
				(type default)
			)
			(layer "B.Fab")
		)
		(fp_line
			(start -0.67945 -0.3048)
			(end -0.67945 0.3048)
			(stroke
				(width 0.1)
				(type default)
			)
			(layer "B.Fab")
		)
		(pad "1" smd circle
			(at 0.40005 0)
			(size 0 0)
			(layers "B.Cu" "B.Mask" "B.Paste")
			(net "RST_SMB_NIC_MUX_R_N")
		)
		(pad "2" smd circle
			(at -0.40005 0)
			(size 0 0)
			(layers "B.Cu" "B.Mask" "B.Paste")
			(net "RST_SMB_NIC3_MUX_N")
		)
	)
	(footprint ""
		(layer "B.Cu")
		(at 47.7774 -300.7995 -90)
		(property "Reference" "C3022"
			(at 0 0 90)
			(layer "B.SilkS")
			(hide yes)
			(effects
				(font
					(size 1.27 1.27)
				)
				(justify mirror)
			)
		)
		(property "Value" ""
			(at 0 0 90)
			(layer "B.Fab")
			(effects
				(font
					(size 1.27 1.27)
				)
				(justify mirror)
			)
		)
		(duplicate_pad_numbers_are_jumpers no)
		(fp_line
			(start -0.299974 0.150114)
			(end 0.299974 0.150114)
			(stroke
				(width 0.1)
				(type default)
			)
			(layer "B.Fab")
		)
		(fp_line
			(start 0.299974 0.150114)
			(end 0.299974 -0.150114)
			(stroke
				(width 0.1)
				(type default)
			)
			(layer "B.Fab")
		)
		(fp_line
			(start -0.299974 -0.150114)
			(end -0.299974 0.150114)
			(stroke
				(width 0.1)
				(type default)
			)
			(layer "B.Fab")
		)
		(fp_line
			(start 0.299974 -0.150114)
			(end -0.299974 -0.150114)
			(stroke
				(width 0.1)
				(type default)
			)
			(layer "B.Fab")
		)
		(pad "1" smd rect
			(at 0.2667 0 90)
			(size 0.3048 0.381)
			(layers "B.Cu" "B.Mask" "B.Paste")
			(net "PCEPLL0_VDDA18_PEX0")
		)
		(pad "2" smd rect
			(at -0.2667 0 90)
			(size 0.3048 0.381)
			(layers "B.Cu" "B.Mask" "B.Paste")
			(net "GND")
		)
	)
	(footprint ""
		(layer "B.Cu")
		(at 172.900086 -292.099746 90)
		(property "Reference" "C1479"
			(at 0 0 90)
			(layer "B.SilkS")
			(hide yes)
			(effects
				(font
					(size 1.27 1.27)
				)
				(justify mirror)
			)
		)
		(property "Value" ""
			(at 0 0 90)
			(layer "B.Fab")
			(effects
				(font
					(size 1.27 1.27)
				)
				(justify mirror)
			)
		)
		(duplicate_pad_numbers_are_jumpers no)
		(fp_line
			(start 0.299974 -0.150114)
			(end -0.299974 -0.150114)
			(stroke
				(width 0.1)
				(type default)
			)
			(layer "B.Fab")
		)
		(fp_line
			(start -0.299974 -0.150114)
			(end -0.299974 0.150114)
			(stroke
				(width 0.1)
				(type default)
			)
			(layer "B.Fab")
		)
		(fp_line
			(start 0.299974 0.150114)
			(end 0.299974 -0.150114)
			(stroke
				(width 0.1)
				(type default)
			)
			(layer "B.Fab")
		)
		(fp_line
			(start -0.299974 0.150114)
			(end 0.299974 0.150114)
			(stroke
				(width 0.1)
				(type default)
			)
			(layer "B.Fab")
		)
		(pad "1" smd rect
			(at 0.2667 0 270)
			(size 0.3048 0.381)
			(layers "B.Cu" "B.Mask" "B.Paste")
			(net "P0V8_SERDES_VDDA_PEX1")
		)
		(pad "2" smd rect
			(at -0.2667 0 270)
			(size 0.3048 0.381)
			(layers "B.Cu" "B.Mask" "B.Paste")
			(net "GND")
		)
	)
	(footprint ""
		(layer "B.Cu")
		(at 71.28637 -117.66169)
		(property "Reference" "R54"
			(at 0 0 0)
			(layer "B.SilkS")
			(hide yes)
			(effects
				(font
					(size 1.27 1.27)
				)
				(justify mirror)
			)
		)
		(property "Value" ""
			(at 0 0 0)
			(layer "B.Fab")
			(effects
				(font
					(size 1.27 1.27)
				)
				(justify mirror)
			)
		)
		(duplicate_pad_numbers_are_jumpers no)
		(fp_line
			(start -0.7874 -0.4064)
			(end -0.7874 0.4064)
			(stroke
				(width 0.1524)
				(type default)
			)
			(layer "B.SilkS")
		)
		(fp_line
			(start -0.7874 0.4064)
			(end 0.7874 0.4064)
			(stroke
				(width 0.1524)
				(type default)
			)
			(layer "B.SilkS")
		)
		(fp_line
			(start 0.7874 -0.4064)
			(end -0.7874 -0.4064)
			(stroke
				(width 0.1524)
				(type default)
			)
			(layer "B.SilkS")
		)
		(fp_line
			(start 0.7874 0.4064)
			(end 0.7874 -0.4064)
			(stroke
				(width 0.1524)
				(type default)
			)
			(layer "B.SilkS")
		)
		(fp_line
			(start -0.67945 -0.3048)
			(end -0.67945 0.3048)
			(stroke
				(width 0.1)
				(type default)
			)
			(layer "B.Fab")
		)
		(fp_line
			(start -0.67945 0.3048)
			(end -0.120396 0.3048)
			(stroke
				(width 0.1)
				(type default)
			)
			(layer "B.Fab")
		)
		(fp_line
			(start -0.12065 -0.3048)
			(end -0.67945 -0.3048)
			(stroke
				(width 0.1)
				(type default)
			)
			(layer "B.Fab")
		)
		(fp_line
			(start -0.12065 -0.2794)
			(end -0.12065 -0.3048)
			(stroke
				(width 0.1)
				(type default)
			)
			(layer "B.Fab")
		)
		(fp_line
			(start -0.120396 0.2794)
			(end 0.12065 0.2794)
			(stroke
				(width 0.1)
				(type default)
			)
			(layer "B.Fab")
		)
		(fp_line
			(start -0.120396 0.3048)
			(end -0.120396 0.2794)
			(stroke
				(width 0.1)
				(type default)
			)
			(layer "B.Fab")
		)
		(fp_line
			(start 0.12065 -0.305054)
			(end 0.12065 -0.2794)
			(stroke
				(width 0.1)
				(type default)
			)
			(layer "B.Fab")
		)
		(fp_line
			(start 0.12065 -0.2794)
			(end -0.12065 -0.2794)
			(stroke
				(width 0.1)
				(type default)
			)
			(layer "B.Fab")
		)
		(fp_line
			(start 0.12065 0.2794)
			(end 0.12065 0.3048)
			(stroke
				(width 0.1)
				(type default)
			)
			(layer "B.Fab")
		)
		(fp_line
			(start 0.12065 0.3048)
			(end 0.67945 0.3048)
			(stroke
				(width 0.1)
				(type default)
			)
			(layer "B.Fab")
		)
		(fp_line
			(start 0.67945 -0.305054)
			(end 0.12065 -0.305054)
			(stroke
				(width 0.1)
				(type default)
			)
			(layer "B.Fab")
		)
		(fp_line
			(start 0.67945 0.3048)
			(end 0.67945 -0.305054)
			(stroke
				(width 0.1)
				(type default)
			)
			(layer "B.Fab")
		)
		(pad "1" smd circle
			(at 0.40005 0 180)
			(size 0 0)
			(layers "B.Cu" "B.Mask" "B.Paste")
			(net "NIC1_AUX_PWR_EN_R")
		)
		(pad "2" smd circle
			(at -0.40005 0 180)
			(size 0 0)
			(layers "B.Cu" "B.Mask" "B.Paste")
			(net "NIC1_AUX_PWR_EN")
		)
	)
	(footprint ""
		(layer "B.Cu")
		(at 75.820778 -114.35207 90)
		(property "Reference" "C867"
			(at 0 0 90)
			(layer "B.SilkS")
			(hide yes)
			(effects
				(font
					(size 1.27 1.27)
				)
				(justify mirror)
			)
		)
		(property "Value" ""
			(at 0 0 90)
			(layer "B.Fab")
			(effects
				(font
					(size 1.27 1.27)
				)
				(justify mirror)
			)
		)
		(duplicate_pad_numbers_are_jumpers no)
		(fp_line
			(start 0.7874 -0.4064)
			(end -0.7874 -0.4064)
			(stroke
				(width 0.1524)
				(type default)
			)
			(layer "B.SilkS")
		)
		(fp_line
			(start -0.7874 -0.4064)
			(end -0.7874 0.4064)
			(stroke
				(width 0.1524)
				(type default)
			)
			(layer "B.SilkS")
		)
		(fp_line
			(start 0.7874 0.4064)
			(end 0.7874 -0.4064)
			(stroke
				(width 0.1524)
				(type default)
			)
			(layer "B.SilkS")
		)
		(fp_line
			(start -0.7874 0.4064)
			(end 0.7874 0.4064)
			(stroke
				(width 0.1524)
				(type default)
			)
			(layer "B.SilkS")
		)
		(fp_line
			(start 0.67945 -0.305054)
			(end 0.12065 -0.305054)
			(stroke
				(width 0.1)
				(type default)
			)
			(layer "B.Fab")
		)
		(fp_line
			(start 0.12065 -0.305054)
			(end 0.12065 -0.2794)
			(stroke
				(width 0.1)
				(type default)
			)
			(layer "B.Fab")
		)
		(fp_line
			(start -0.12065 -0.3048)
			(end -0.67945 -0.3048)
			(stroke
				(width 0.1)
				(type default)
			)
			(layer "B.Fab")
		)
		(fp_line
			(start -0.67945 -0.3048)
			(end -0.67945 0.3048)
			(stroke
				(width 0.1)
				(type default)
			)
			(layer "B.Fab")
		)
		(fp_line
			(start 0.12065 -0.2794)
			(end -0.12065 -0.2794)
			(stroke
				(width 0.1)
				(type default)
			)
			(layer "B.Fab")
		)
		(fp_line
			(start -0.12065 -0.2794)
			(end -0.12065 -0.3048)
			(stroke
				(width 0.1)
				(type default)
			)
			(layer "B.Fab")
		)
		(fp_line
			(start 0.12065 0.2794)
			(end 0.12065 0.3048)
			(stroke
				(width 0.1)
				(type default)
			)
			(layer "B.Fab")
		)
		(fp_line
			(start -0.120396 0.2794)
			(end 0.12065 0.2794)
			(stroke
				(width 0.1)
				(type default)
			)
			(layer "B.Fab")
		)
		(fp_line
			(start 0.67945 0.3048)
			(end 0.67945 -0.305054)
			(stroke
				(width 0.1)
				(type default)
			)
			(layer "B.Fab")
		)
		(fp_line
			(start 0.12065 0.3048)
			(end 0.67945 0.3048)
			(stroke
				(width 0.1)
				(type default)
			)
			(layer "B.Fab")
		)
		(fp_line
			(start -0.120396 0.3048)
			(end -0.120396 0.2794)
			(stroke
				(width 0.1)
				(type default)
			)
			(layer "B.Fab")
		)
		(fp_line
			(start -0.67945 0.3048)
			(end -0.120396 0.3048)
			(stroke
				(width 0.1)
				(type default)
			)
			(layer "B.Fab")
		)
		(pad "1" smd circle
			(at 0.40005 0 270)
			(size 0 0)
			(layers "B.Cu" "B.Mask" "B.Paste")
			(net "P3V3_NIC1")
		)
		(pad "2" smd circle
			(at -0.40005 0 270)
			(size 0 0)
			(layers "B.Cu" "B.Mask" "B.Paste")
			(net "GND")
		)
	)
	(footprint ""
		(layer "B.Cu")
		(at 262.967724 -82.487008)
		(property "Reference" "C2633"
			(at 0 0 0)
			(layer "B.SilkS")
			(hide yes)
			(effects
				(font
					(size 1.27 1.27)
				)
				(justify mirror)
			)
		)
		(property "Value" ""
			(at 0 0 0)
			(layer "B.Fab")
			(effects
				(font
					(size 1.27 1.27)
				)
				(justify mirror)
			)
		)
		(duplicate_pad_numbers_are_jumpers no)
		(fp_line
			(start -0.7874 -0.4064)
			(end -0.7874 0.4064)
			(stroke
				(width 0.1524)
				(type default)
			)
			(layer "B.SilkS")
		)
		(fp_line
			(start -0.7874 0.4064)
			(end 0.7874 0.4064)
			(stroke
				(width 0.1524)
				(type default)
			)
			(layer "B.SilkS")
		)
		(fp_line
			(start 0.7874 -0.4064)
			(end -0.7874 -0.4064)
			(stroke
				(width 0.1524)
				(type default)
			)
			(layer "B.SilkS")
		)
		(fp_line
			(start 0.7874 0.4064)
			(end 0.7874 -0.4064)
			(stroke
				(width 0.1524)
				(type default)
			)
			(layer "B.SilkS")
		)
		(fp_line
			(start -0.67945 -0.3048)
			(end -0.67945 0.3048)
			(stroke
				(width 0.1)
				(type default)
			)
			(layer "B.Fab")
		)
		(fp_line
			(start -0.67945 0.3048)
			(end -0.120396 0.3048)
			(stroke
				(width 0.1)
				(type default)
			)
			(layer "B.Fab")
		)
		(fp_line
			(start -0.12065 -0.3048)
			(end -0.67945 -0.3048)
			(stroke
				(width 0.1)
				(type default)
			)
			(layer "B.Fab")
		)
		(fp_line
			(start -0.12065 -0.2794)
			(end -0.12065 -0.3048)
			(stroke
				(width 0.1)
				(type default)
			)
			(layer "B.Fab")
		)
		(fp_line
			(start -0.120396 0.2794)
			(end 0.12065 0.2794)
			(stroke
				(width 0.1)
				(type default)
			)
			(layer "B.Fab")
		)
		(fp_line
			(start -0.120396 0.3048)
			(end -0.120396 0.2794)
			(stroke
				(width 0.1)
				(type default)
			)
			(layer "B.Fab")
		)
		(fp_line
			(start 0.12065 -0.305054)
			(end 0.12065 -0.2794)
			(stroke
				(width 0.1)
				(type default)
			)
			(layer "B.Fab")
		)
		(fp_line
			(start 0.12065 -0.2794)
			(end -0.12065 -0.2794)
			(stroke
				(width 0.1)
				(type default)
			)
			(layer "B.Fab")
		)
		(fp_line
			(start 0.12065 0.2794)
			(end 0.12065 0.3048)
			(stroke
				(width 0.1)
				(type default)
			)
			(layer "B.Fab")
		)
		(fp_line
			(start 0.12065 0.3048)
			(end 0.67945 0.3048)
			(stroke
				(width 0.1)
				(type default)
			)
			(layer "B.Fab")
		)
		(fp_line
			(start 0.67945 -0.305054)
			(end 0.12065 -0.305054)
			(stroke
				(width 0.1)
				(type default)
			)
			(layer "B.Fab")
		)
		(fp_line
			(start 0.67945 0.3048)
			(end 0.67945 -0.305054)
			(stroke
				(width 0.1)
				(type default)
			)
			(layer "B.Fab")
		)
		(pad "1" smd circle
			(at 0.40005 0 180)
			(size 0 0)
			(layers "B.Cu" "B.Mask" "B.Paste")
			(net "P3V3_CLK_GEN_VDD_CK440")
		)
		(pad "2" smd circle
			(at -0.40005 0 180)
			(size 0 0)
			(layers "B.Cu" "B.Mask" "B.Paste")
			(net "GND")
		)
	)
	(footprint ""
		(layer "B.Cu")
		(at 309.741824 -101.069648 180)
		(property "Reference" "R280"
			(at 0 0 0)
			(layer "B.SilkS")
			(hide yes)
			(effects
				(font
					(size 1.27 1.27)
				)
				(justify mirror)
			)
		)
		(property "Value" ""
			(at 0 0 0)
			(layer "B.Fab")
			(effects
				(font
					(size 1.27 1.27)
				)
				(justify mirror)
			)
		)
		(duplicate_pad_numbers_are_jumpers no)
		(fp_line
			(start 0.7874 0.4064)
			(end 0.7874 -0.4064)
			(stroke
				(width 0.1524)
				(type default)
			)
			(layer "B.SilkS")
		)
		(fp_line
			(start 0.7874 -0.4064)
			(end -0.7874 -0.4064)
			(stroke
				(width 0.1524)
				(type default)
			)
			(layer "B.SilkS")
		)
		(fp_line
			(start -0.7874 0.4064)
			(end 0.7874 0.4064)
			(stroke
				(width 0.1524)
				(type default)
			)
			(layer "B.SilkS")
		)
		(fp_line
			(start -0.7874 -0.4064)
			(end -0.7874 0.4064)
			(stroke
				(width 0.1524)
				(type default)
			)
			(layer "B.SilkS")
		)
		(fp_line
			(start 0.67945 0.3048)
			(end 0.67945 -0.305054)
			(stroke
				(width 0.1)
				(type default)
			)
			(layer "B.Fab")
		)
		(fp_line
			(start 0.67945 -0.305054)
			(end 0.12065 -0.305054)
			(stroke
				(width 0.1)
				(type default)
			)
			(layer "B.Fab")
		)
		(fp_line
			(start 0.12065 0.3048)
			(end 0.67945 0.3048)
			(stroke
				(width 0.1)
				(type default)
			)
			(layer "B.Fab")
		)
		(fp_line
			(start 0.12065 0.2794)
			(end 0.12065 0.3048)
			(stroke
				(width 0.1)
				(type default)
			)
			(layer "B.Fab")
		)
		(fp_line
			(start 0.12065 -0.2794)
			(end -0.12065 -0.2794)
			(stroke
				(width 0.1)
				(type default)
			)
			(layer "B.Fab")
		)
		(fp_line
			(start 0.12065 -0.305054)
			(end 0.12065 -0.2794)
			(stroke
				(width 0.1)
				(type default)
			)
			(layer "B.Fab")
		)
		(fp_line
			(start -0.120396 0.3048)
			(end -0.120396 0.2794)
			(stroke
				(width 0.1)
				(type default)
			)
			(layer "B.Fab")
		)
		(fp_line
			(start -0.120396 0.2794)
			(end 0.12065 0.2794)
			(stroke
				(width 0.1)
				(type default)
			)
			(layer "B.Fab")
		)
		(fp_line
			(start -0.12065 -0.2794)
			(end -0.12065 -0.3048)
			(stroke
				(width 0.1)
				(type default)
			)
			(layer "B.Fab")
		)
		(fp_line
			(start -0.12065 -0.3048)
			(end -0.67945 -0.3048)
			(stroke
				(width 0.1)
				(type default)
			)
			(layer "B.Fab")
		)
		(fp_line
			(start -0.67945 0.3048)
			(end -0.120396 0.3048)
			(stroke
				(width 0.1)
				(type default)
			)
			(layer "B.Fab")
		)
		(fp_line
			(start -0.67945 -0.3048)
			(end -0.67945 0.3048)
			(stroke
				(width 0.1)
				(type default)
			)
			(layer "B.Fab")
		)
		(pad "1" smd circle
			(at 0.40005 0)
			(size 0 0)
			(layers "B.Cu" "B.Mask" "B.Paste")
			(net "NIC5_SLOT_ID0")
		)
		(pad "2" smd circle
			(at -0.40005 0)
			(size 0 0)
			(layers "B.Cu" "B.Mask" "B.Paste")
			(net "P3V3_NIC5")
		)
	)
)
